# BASEBOARD_FAB2 (Tioga Pass) — schematic netlist excerpt (pin names and nets, part order shuffled) for the footprints in the layout excerpt that follows; sources: Cadence DE-HDL packaged netlist, KiCad conversion of Wiwynn_Tioga_Pass_MB.brd

C9E8  CAP  15.0PF 50V 5% COG  pkg 0402LF  page 139 : A = XTAL_25MHZ_OUT_R ; B = GND
R7C8  RES  10.0K 1% CHIP  pkg 0402  page 133 : A = P3V3_STBY ; B = FM_WBG_PRSNT_N
L7A1  IND-120NH-30-GP  pkg DISCRET-GB2  page 219 : S = VR_PVDDQ_DEF_PH1_SW ; F = PVDDQ_DEF

(kicad_pcb
	(version 20260206)
	(generator "pcbnew")
	(generator_version "10.0")
	(general
		(thickness 1.6)
		(legacy_teardrops no)
	)
	(paper "A4")
	(title_block
		(title "Wiwynn_Tioga_Pass_MB.brd")
		(comment 1 "Tioga Pass / footprints 1299-1301 of 4770")
	)
	(layers
		(0 "F.Cu" signal "TOP")
		(4 "In1.Cu" signal "L2GND")
		(6 "In2.Cu" signal "L3")
		(8 "In3.Cu" signal "L4GND")
		(10 "In4.Cu" signal "L5")
		(12 "In5.Cu" signal "L6GND")
		(14 "In6.Cu" signal "L7VCC")
		(16 "In7.Cu" signal "L8VCC")
		(18 "In8.Cu" signal "L9GND")
		(20 "In9.Cu" signal "L10")
		(22 "In10.Cu" signal "L11GND")
		(24 "In11.Cu" signal "L12")
		(26 "In12.Cu" signal "L13GND")
		(2 "B.Cu" signal "BOTTOM")
		(9 "F.Adhes" user "F.Adhesive")
		(11 "B.Adhes" user "B.Adhesive")
		(13 "F.Paste" user "Package Geometry/Pastemask Top")
		(15 "B.Paste" user "Package Geometry/Pastemask Bottom")
		(5 "F.SilkS" user "Ref Des/Silkscreen Top")
		(7 "B.SilkS" user "Ref Des/Silkscreen Bottom")
		(1 "F.Mask" user "Board Geometry/Soldermask Top")
		(3 "B.Mask" user "Board Geometry/Soldermask Bottom")
		(17 "Dwgs.User" user "User.Drawings")
		(19 "Cmts.User" user "User.Comments")
		(21 "Eco1.User" user "User.Eco1")
		(23 "Eco2.User" user "User.Eco2")
		(25 "Edge.Cuts" user "Board Geometry/Outline")
		(27 "Margin" user)
		(31 "F.CrtYd" user "Package Geometry/Place Bound Top")
		(29 "B.CrtYd" user "Package Geometry/Place Bound Bottom")
		(35 "F.Fab" user "Ref Des/Assembly Top")
		(33 "B.Fab" user "Ref Des/Assembly Bottom")
	)
	(footprint ""
		(layer "F.Cu")
		(at 368.554 -94.742 90)
		(property "Reference" "R7C8"
			(at 0 0 90)
			(layer "F.SilkS")
			(hide yes)
			(effects
				(font
					(size 1.27 1.27)
				)
			)
		)
		(property "Value" ""
			(at 0 0 90)
			(layer "F.Fab")
			(effects
				(font
					(size 1.27 1.27)
				)
			)
		)
		(duplicate_pad_numbers_are_jumpers no)
		(fp_poly
			(pts
				(xy -0.2794 -0.1016) (xy 0.2794 -0.1016) (xy 0.2794 0.9906) (xy -0.2794 0.9906)
			)
			(stroke
				(width 0)
				(type default)
			)
			(fill no)
			(layer "F.CrtYd")
		)
		(fp_line
			(start 0.2794 -0.1016)
			(end -0.2794 -0.1016)
			(stroke
				(width 0.1)
				(type default)
			)
			(layer "F.Fab")
		)
		(fp_line
			(start -0.2794 -0.1016)
			(end -0.2794 0.9906)
			(stroke
				(width 0.1)
				(type default)
			)
			(layer "F.Fab")
		)
		(fp_line
			(start 0.2794 0.9906)
			(end 0.2794 -0.1016)
			(stroke
				(width 0.1)
				(type default)
			)
			(layer "F.Fab")
		)
		(fp_line
			(start -0.2794 0.9906)
			(end 0.2794 0.9906)
			(stroke
				(width 0.1)
				(type default)
			)
			(layer "F.Fab")
		)
		(pad "1" smd rect
			(at 0 0 90)
			(size 0.508 0.508)
			(layers "F.Cu" "F.Mask" "F.Paste")
			(net "P3V3_STBY")
		)
		(pad "2" smd rect
			(at 0 0.889 90)
			(size 0.508 0.508)
			(layers "F.Cu" "F.Mask" "F.Paste")
			(net "FM_WBG_PRSNT_N")
		)
		(zone
			(layer "F.Cu")
			(hatch none 0.5)
			(connect_pads
				(clearance 0)
			)
			(min_thickness 0.25)
			(keepout
				(tracks allowed)
				(vias not_allowed)
				(pads allowed)
				(copperpour not_allowed)
				(footprints allowed)
			)
			(placement
				(enabled no)
				(sheetname "")
			)
			(fill
				(thermal_gap 0.5)
				(thermal_bridge_width 0.5)
				(island_removal_mode 0)
			)
			(polygon
				(pts
					(xy 368.808 -94.488) (xy 368.808 -94.996) (xy 369.189 -94.996) (xy 369.189 -94.488)
				)
			)
		)
		(zone
			(layer "F.Cu")
			(hatch none 0.5)
			(connect_pads
				(clearance 0)
			)
			(min_thickness 0.25)
			(keepout
				(tracks not_allowed)
				(vias allowed)
				(pads allowed)
				(copperpour not_allowed)
				(footprints allowed)
			)
			(placement
				(enabled no)
				(sheetname "")
			)
			(fill
				(thermal_gap 0.5)
				(thermal_bridge_width 0.5)
				(island_removal_mode 0)
			)
			(polygon
				(pts
					(xy 369.189 -94.488) (xy 369.189 -94.996) (xy 368.808 -94.996) (xy 368.808 -94.488)
				)
			)
		)
	)
	(footprint ""
		(layer "F.Cu")
		(at 341.3252 -154.801824 180)
		(property "Reference" "L7A1"
			(at 3.378708 -4.251706 180)
			(unlocked yes)
			(layer "F.SilkS")
			(effects
				(font
					(size 0.4064 0.254)
					(thickness 0.1524)
				)
			)
		)
		(property "Value" ""
			(at 0 0 180)
			(layer "F.Fab")
			(effects
				(font
					(size 1.27 1.27)
				)
			)
		)
		(duplicate_pad_numbers_are_jumpers no)
		(fp_line
			(start 8.3693 3.199892)
			(end -1.1303 3.199892)
			(stroke
				(width 0.1524)
				(type default)
			)
			(layer "F.SilkS")
		)
		(fp_line
			(start 8.3693 1.6637)
			(end 8.3693 3.199892)
			(stroke
				(width 0.1524)
				(type default)
			)
			(layer "F.SilkS")
		)
		(fp_line
			(start 8.3693 -3.199892)
			(end 8.3693 -1.6637)
			(stroke
				(width 0.1524)
				(type default)
			)
			(layer "F.SilkS")
		)
		(fp_line
			(start -1.1303 3.199892)
			(end -1.1303 1.6637)
			(stroke
				(width 0.1524)
				(type default)
			)
			(layer "F.SilkS")
		)
		(fp_line
			(start -1.1303 -1.6637)
			(end -1.1303 -3.199892)
			(stroke
				(width 0.1524)
				(type default)
			)
			(layer "F.SilkS")
		)
		(fp_line
			(start -1.1303 -3.199892)
			(end 8.3693 -3.199892)
			(stroke
				(width 0.1524)
				(type default)
			)
			(layer "F.SilkS")
		)
		(fp_rect
			(start -1.1303 3.199892)
			(end 8.3693 -3.199892)
			(stroke
				(width 0)
				(type default)
			)
			(fill no)
			(layer "F.CrtYd")
		)
		(fp_line
			(start 8.3693 3.199892)
			(end -1.1303 3.199892)
			(stroke
				(width 0.1)
				(type default)
			)
			(layer "F.Fab")
		)
		(fp_line
			(start 8.3693 -3.199892)
			(end 8.3693 3.199892)
			(stroke
				(width 0.1)
				(type default)
			)
			(layer "F.Fab")
		)
		(fp_line
			(start -1.1303 3.199892)
			(end -1.1303 -3.199892)
			(stroke
				(width 0.1)
				(type default)
			)
			(layer "F.Fab")
		)
		(fp_line
			(start -1.1303 -3.199892)
			(end 8.3693 -3.199892)
			(stroke
				(width 0.1)
				(type default)
			)
			(layer "F.Fab")
		)
		(pad "1" smd rect
			(at 0 0 180)
			(size 3.683 2.667)
			(layers "F.Cu" "F.Mask" "F.Paste")
			(net "VR_PVDDQ_DEF_PH1_SW")
		)
		(pad "2" smd rect
			(at 7.239 0 180)
			(size 3.683 2.667)
			(layers "F.Cu" "F.Mask" "F.Paste")
			(net "PVDDQ_DEF")
		)
	)
	(footprint ""
		(layer "F.Cu")
		(at 476.4786 -41.9989 180)
		(property "Reference" "C9E8"
			(at 0 0 180)
			(layer "F.SilkS")
			(hide yes)
			(effects
				(font
					(size 1.27 1.27)
				)
			)
		)
		(property "Value" ""
			(at 0 0 180)
			(layer "F.Fab")
			(effects
				(font
					(size 1.27 1.27)
				)
			)
		)
		(duplicate_pad_numbers_are_jumpers no)
		(fp_poly
			(pts
				(xy 0.3048 -0.1016) (xy 0.3048 0.9906) (xy -0.3048 0.9906) (xy -0.3048 -0.1016)
			)
			(stroke
				(width 0)
				(type default)
			)
			(fill no)
			(layer "F.CrtYd")
		)
		(fp_line
			(start 0.3048 0.9906)
			(end 0.3048 -0.1016)
			(stroke
				(width 0.1)
				(type default)
			)
			(layer "F.Fab")
		)
		(fp_line
			(start 0.3048 -0.1016)
			(end -0.3048 -0.1016)
			(stroke
				(width 0.1)
				(type default)
			)
			(layer "F.Fab")
		)
		(fp_line
			(start -0.3048 0.9906)
			(end 0.3048 0.9906)
			(stroke
				(width 0.1)
				(type default)
			)
			(layer "F.Fab")
		)
		(fp_line
			(start -0.3048 -0.1016)
			(end -0.3048 0.9906)
			(stroke
				(width 0.1)
				(type default)
			)
			(layer "F.Fab")
		)
		(pad "1" smd rect
			(at 0 0 180)
			(size 0.508 0.508)
			(layers "F.Cu" "F.Mask" "F.Paste")
			(net "XTAL_25MHZ_OUT_R")
		)
		(pad "2" smd rect
			(at 0 0.889 180)
			(size 0.508 0.508)
			(layers "F.Cu" "F.Mask" "F.Paste")
			(net "GND")
		)
		(zone
			(layer "F.Cu")
			(hatch none 0.5)
			(connect_pads
				(clearance 0)
			)
			(min_thickness 0.25)
			(keepout
				(tracks not_allowed)
				(vias allowed)
				(pads allowed)
				(copperpour not_allowed)
				(footprints allowed)
			)
			(placement
				(enabled no)
				(sheetname "")
			)
			(fill
				(thermal_gap 0.5)
				(thermal_bridge_width 0.5)
				(island_removal_mode 0)
			)
			(polygon
				(pts
					(xy 476.7326 -42.6339) (xy 476.2246 -42.6339) (xy 476.2246 -42.2529) (xy 476.7326 -42.2529)
				)
			)
		)
		(zone
			(layer "F.Cu")
			(hatch none 0.5)
			(connect_pads
				(clearance 0)
			)
			(min_thickness 0.25)
			(keepout
				(tracks allowed)
				(vias not_allowed)
				(pads allowed)
				(copperpour not_allowed)
				(footprints allowed)
			)
			(placement
				(enabled no)
				(sheetname "")
			)
			(fill
				(thermal_gap 0.5)
				(thermal_bridge_width 0.5)
				(island_removal_mode 0)
			)
			(polygon
				(pts
					(xy 476.7326 -42.2529) (xy 476.2246 -42.2529) (xy 476.2246 -42.6339) (xy 476.7326 -42.6339)
				)
			)
		)
	)
)
